# T6G (Grand Teton) — schematic netlist excerpt (pin names and nets, part order shuffled) for the footprints in the layout excerpt that follows; sources: Cadence DE-HDL packaged netlist, KiCad conversion of 04192023_DAF0TMB3IC0_F0TG_MB_C_brd_V02_OCP.brd

R8063  Q_RES  100 1% CHIP  pkg 0402LF  page 200 : A = PVDDCR_CPU1_P0_RESET_N ; B = PVDDCR_CPU1_P0_RESET_N_R
R1595  Q_RES  33.2 1% CHIP  pkg 0402LF  page 133 : A = OCP_SFF_PWRBRK_BUFF_N ; B = OCP_SFF_PWRBRK_N

(kicad_pcb
	(version 20260206)
	(generator "pcbnew")
	(generator_version "10.0")
	(general
		(thickness 1.6)
		(legacy_teardrops no)
	)
	(paper "A4")
	(title_block
		(title "04192023_DAF0TMB3IC0_F0TG_MB_C_brd_V02_OCP.brd")
		(comment 1 "Grand Teton / footprints 1779-1780 of 8354")
	)
	(layers
		(0 "F.Cu" signal "TOP")
		(4 "In1.Cu" signal "GND")
		(6 "In2.Cu" signal "IN1")
		(8 "In3.Cu" signal "GND1")
		(10 "In4.Cu" signal "IN2")
		(12 "In5.Cu" signal "GND2")
		(14 "In6.Cu" signal "IN3")
		(16 "In7.Cu" signal "GND3")
		(18 "In8.Cu" signal "VCC")
		(20 "In9.Cu" signal "VCC1")
		(22 "In10.Cu" signal "GND4")
		(24 "In11.Cu" signal "IN4")
		(26 "In12.Cu" signal "GND5")
		(28 "In13.Cu" signal "IN5")
		(30 "In14.Cu" signal "GND6")
		(32 "In15.Cu" signal "IN6")
		(34 "In16.Cu" signal "GND7")
		(2 "B.Cu" signal "BOTTOM")
		(9 "F.Adhes" user "F.Adhesive")
		(11 "B.Adhes" user "B.Adhesive")
		(13 "F.Paste" user "Package Geometry/Pastemask Top")
		(15 "B.Paste" user "Package Geometry/Pastemask Bottom")
		(5 "F.SilkS" user "Ref Des/Silkscreen Top")
		(7 "B.SilkS" user "Ref Des/Silkscreen Bottom")
		(1 "F.Mask" user "Board Geometry/Soldermask Top")
		(3 "B.Mask" user "Board Geometry/Soldermask Bottom")
		(17 "Dwgs.User" user "User.Drawings")
		(19 "Cmts.User" user "User.Comments")
		(21 "Eco1.User" user "User.Eco1")
		(23 "Eco2.User" user "User.Eco2")
		(25 "Edge.Cuts" user "Board Geometry/Outline")
		(27 "Margin" user)
		(31 "F.CrtYd" user "Package Geometry/Place Bound Top")
		(29 "B.CrtYd" user "Package Geometry/Place Bound Bottom")
		(35 "F.Fab" user "Ref Des/Assembly Top")
		(33 "B.Fab" user "Ref Des/Assembly Bottom")
	)
	(footprint ""
		(layer "F.Cu")
		(at 374.24487 -15.637002)
		(property "Reference" "R1595"
			(at 0 0 0)
			(layer "F.SilkS")
			(hide yes)
			(effects
				(font
					(size 1.27 1.27)
				)
			)
		)
		(property "Value" ""
			(at 0 0 0)
			(layer "F.Fab")
			(effects
				(font
					(size 1.27 1.27)
				)
			)
		)
		(duplicate_pad_numbers_are_jumpers no)
		(fp_line
			(start -0.7874 -0.4064)
			(end 0.7874 -0.4064)
			(stroke
				(width 0.1524)
				(type default)
			)
			(layer "F.SilkS")
		)
		(fp_line
			(start -0.7874 0.4064)
			(end -0.7874 -0.4064)
			(stroke
				(width 0.1524)
				(type default)
			)
			(layer "F.SilkS")
		)
		(fp_line
			(start 0.7874 -0.4064)
			(end 0.7874 0.4064)
			(stroke
				(width 0.1524)
				(type default)
			)
			(layer "F.SilkS")
		)
		(fp_line
			(start 0.7874 0.4064)
			(end -0.7874 0.4064)
			(stroke
				(width 0.1524)
				(type default)
			)
			(layer "F.SilkS")
		)
		(fp_line
			(start -0.67945 -0.305054)
			(end -0.12065 -0.305054)
			(stroke
				(width 0.1)
				(type default)
			)
			(layer "F.Fab")
		)
		(fp_line
			(start -0.67945 0.3048)
			(end -0.67945 -0.305054)
			(stroke
				(width 0.1)
				(type default)
			)
			(layer "F.Fab")
		)
		(fp_line
			(start -0.12065 -0.305054)
			(end -0.12065 -0.2794)
			(stroke
				(width 0.1)
				(type default)
			)
			(layer "F.Fab")
		)
		(fp_line
			(start -0.12065 -0.2794)
			(end 0.12065 -0.2794)
			(stroke
				(width 0.1)
				(type default)
			)
			(layer "F.Fab")
		)
		(fp_line
			(start -0.12065 0.2794)
			(end -0.12065 0.3048)
			(stroke
				(width 0.1)
				(type default)
			)
			(layer "F.Fab")
		)
		(fp_line
			(start -0.12065 0.3048)
			(end -0.67945 0.3048)
			(stroke
				(width 0.1)
				(type default)
			)
			(layer "F.Fab")
		)
		(fp_line
			(start 0.120396 0.2794)
			(end -0.12065 0.2794)
			(stroke
				(width 0.1)
				(type default)
			)
			(layer "F.Fab")
		)
		(fp_line
			(start 0.120396 0.3048)
			(end 0.120396 0.2794)
			(stroke
				(width 0.1)
				(type default)
			)
			(layer "F.Fab")
		)
		(fp_line
			(start 0.12065 -0.3048)
			(end 0.67945 -0.3048)
			(stroke
				(width 0.1)
				(type default)
			)
			(layer "F.Fab")
		)
		(fp_line
			(start 0.12065 -0.2794)
			(end 0.12065 -0.3048)
			(stroke
				(width 0.1)
				(type default)
			)
			(layer "F.Fab")
		)
		(fp_line
			(start 0.67945 -0.3048)
			(end 0.67945 0.3048)
			(stroke
				(width 0.1)
				(type default)
			)
			(layer "F.Fab")
		)
		(fp_line
			(start 0.67945 0.3048)
			(end 0.120396 0.3048)
			(stroke
				(width 0.1)
				(type default)
			)
			(layer "F.Fab")
		)
		(pad "1" smd circle
			(at -0.40005 0)
			(size 0 0)
			(layers "F.Cu" "F.Mask" "F.Paste")
			(net "OCP_SFF_PWRBRK_BUFF_N")
		)
		(pad "2" smd circle
			(at 0.40005 0)
			(size 0 0)
			(layers "F.Cu" "F.Mask" "F.Paste")
			(net "OCP_SFF_PWRBRK_N")
		)
	)
	(footprint ""
		(layer "F.Cu")
		(at 304.419 -361.696)
		(property "Reference" "R8063"
			(at 0 0 0)
			(layer "F.SilkS")
			(hide yes)
			(effects
				(font
					(size 1.27 1.27)
				)
			)
		)
		(property "Value" ""
			(at 0 0 0)
			(layer "F.Fab")
			(effects
				(font
					(size 1.27 1.27)
				)
			)
		)
		(duplicate_pad_numbers_are_jumpers no)
		(fp_line
			(start -0.7874 -0.4064)
			(end 0.7874 -0.4064)
			(stroke
				(width 0.1524)
				(type default)
			)
			(layer "F.SilkS")
		)
		(fp_line
			(start -0.7874 0.4064)
			(end -0.7874 -0.4064)
			(stroke
				(width 0.1524)
				(type default)
			)
			(layer "F.SilkS")
		)
		(fp_line
			(start 0.7874 -0.4064)
			(end 0.7874 0.4064)
			(stroke
				(width 0.1524)
				(type default)
			)
			(layer "F.SilkS")
		)
		(fp_line
			(start 0.7874 0.4064)
			(end -0.7874 0.4064)
			(stroke
				(width 0.1524)
				(type default)
			)
			(layer "F.SilkS")
		)
		(fp_line
			(start -0.67945 -0.305054)
			(end -0.12065 -0.305054)
			(stroke
				(width 0.1)
				(type default)
			)
			(layer "F.Fab")
		)
		(fp_line
			(start -0.67945 0.3048)
			(end -0.67945 -0.305054)
			(stroke
				(width 0.1)
				(type default)
			)
			(layer "F.Fab")
		)
		(fp_line
			(start -0.12065 -0.305054)
			(end -0.12065 -0.2794)
			(stroke
				(width 0.1)
				(type default)
			)
			(layer "F.Fab")
		)
		(fp_line
			(start -0.12065 -0.2794)
			(end 0.12065 -0.2794)
			(stroke
				(width 0.1)
				(type default)
			)
			(layer "F.Fab")
		)
		(fp_line
			(start -0.12065 0.2794)
			(end -0.12065 0.3048)
			(stroke
				(width 0.1)
				(type default)
			)
			(layer "F.Fab")
		)
		(fp_line
			(start -0.12065 0.3048)
			(end -0.67945 0.3048)
			(stroke
				(width 0.1)
				(type default)
			)
			(layer "F.Fab")
		)
		(fp_line
			(start 0.120396 0.2794)
			(end -0.12065 0.2794)
			(stroke
				(width 0.1)
				(type default)
			)
			(layer "F.Fab")
		)
		(fp_line
			(start 0.120396 0.3048)
			(end 0.120396 0.2794)
			(stroke
				(width 0.1)
				(type default)
			)
			(layer "F.Fab")
		)
		(fp_line
			(start 0.12065 -0.3048)
			(end 0.67945 -0.3048)
			(stroke
				(width 0.1)
				(type default)
			)
			(layer "F.Fab")
		)
		(fp_line
			(start 0.12065 -0.2794)
			(end 0.12065 -0.3048)
			(stroke
				(width 0.1)
				(type default)
			)
			(layer "F.Fab")
		)
		(fp_line
			(start 0.67945 -0.3048)
			(end 0.67945 0.3048)
			(stroke
				(width 0.1)
				(type default)
			)
			(layer "F.Fab")
		)
		(fp_line
			(start 0.67945 0.3048)
			(end 0.120396 0.3048)
			(stroke
				(width 0.1)
				(type default)
			)
			(layer "F.Fab")
		)
		(pad "1" smd circle
			(at -0.40005 0)
			(size 0 0)
			(layers "F.Cu" "F.Mask" "F.Paste")
			(net "PVDDCR_CPU1_P0_RESET_N")
		)
		(pad "2" smd circle
			(at 0.40005 0)
			(size 0 0)
			(layers "F.Cu" "F.Mask" "F.Paste")
			(net "PVDDCR_CPU1_P0_RESET_N_R")
		)
	)
)
